(kicad_pcb
	(version 20260206)
	(generator "pcbnew")
	(generator_version "10.0")
	(general
		(thickness 1.6)
		(legacy_teardrops no)
	)
	(paper "A4")
	(title_block
		(title "ptb — Lightning_PTB_BRD.brd")
		(comment 1 "Lightning (Wiwynn / Facebook NVMe JBOF) / footprints 33-35 of 61")
	)
	(layers
		(0 "F.Cu" signal "TOP")
		(4 "In1.Cu" signal "L2GND")
		(6 "In2.Cu" signal "L3VCC")
		(2 "B.Cu" signal "BOTTOM")
		(9 "F.Adhes" user "F.Adhesive")
		(11 "B.Adhes" user "B.Adhesive")
		(13 "F.Paste" user "Package Geometry/Pastemask Top")
		(15 "B.Paste" user "Package Geometry/Pastemask Bottom")
		(5 "F.SilkS" user "Ref Des/Silkscreen Top")
		(7 "B.SilkS" user "Ref Des/Silkscreen Bottom")
		(1 "F.Mask" user "Board Geometry/Soldermask Top")
		(3 "B.Mask" user "Board Geometry/Soldermask Bottom")
		(17 "Dwgs.User" user "User.Drawings")
		(19 "Cmts.User" user "User.Comments")
		(21 "Eco1.User" user "User.Eco1")
		(23 "Eco2.User" user "User.Eco2")
		(25 "Edge.Cuts" user "Board Geometry/Outline")
		(27 "Margin" user)
		(31 "F.CrtYd" user "Package Geometry/Place Bound Top")
		(29 "B.CrtYd" user "Package Geometry/Place Bound Bottom")
		(35 "F.Fab" user "Ref Des/Assembly Top")
		(33 "B.Fab" user "Ref Des/Assembly Bottom")
	)
	(footprint ""
		(layer "F.Cu")
		(at -9.50087 -74.529188 -90)
		(property "Reference" "GF1"
			(at 0 0 270)
			(layer "F.SilkS")
			(hide yes)
			(effects
				(font
					(size 1.27 1.27)
				)
			)
		)
		(property "Value" "GF-36P-24P-GP"
			(at -19.5834 -9.482582 270)
			(unlocked yes)
			(layer "F.Fab")
			(hide yes)
			(effects
				(font
					(size 1.016 1.016)
					(thickness 0.1524)
				)
			)
		)
		(property "Device Type" "GF-36P-24P"
			(at -19.5834 -11.006582 270)
			(unlocked yes)
			(layer "F.Fab")
			(hide yes)
			(effects
				(font
					(size 1.016 1.016)
					(thickness 0.1524)
				)
			)
		)
		(duplicate_pad_numbers_are_jumpers no)
		(fp_rect
			(start -18.6436 2.032)
			(end 47.3964 -8.3312)
			(stroke
				(width 0)
				(type default)
			)
			(fill no)
			(layer "B.CrtYd")
		)
		(fp_rect
			(start -18.6436 2.032)
			(end 47.3964 -8.3312)
			(stroke
				(width 0)
				(type default)
			)
			(fill no)
			(layer "F.CrtYd")
		)
		(fp_rect
			(start -18.6436 2.032)
			(end 47.3964 -8.3312)
			(stroke
				(width 0)
				(type default)
			)
			(fill no)
			(layer "B.Fab")
		)
		(fp_rect
			(start -18.6436 2.032)
			(end 47.3964 -8.3312)
			(stroke
				(width 0)
				(type default)
			)
			(fill no)
			(layer "F.Fab")
		)
		(fp_text user "02 Do not mirror"
			(at 5.969 3.437636 270)
			(unlocked yes)
			(layer "F.Fab")
			(effects
				(font
					(size 1.016 1.016)
					(thickness 0.1524)
				)
				(justify left)
			)
		)
		(pad "P1" smd rect
			(at 40.64 -3.5306 270)
			(size 9.4488 6.2992)
			(drill
				(offset 0 0.381)
			)
			(layers "F.Cu" "F.Mask" "F.Paste")
			(net "P12V")
		)
		(pad "P2" smd rect
			(at 38.2778 -3.9116 270)
			(size 0.0254 0.0254)
			(layers "F.Cu" "F.Mask" "F.Paste")
			(net "P12V")
		)
		(pad "P3" smd rect
			(at 40.64 -3.9116 270)
			(size 0.0254 0.0254)
			(layers "F.Cu" "F.Mask" "F.Paste")
			(net "P12V")
		)
		(pad "P4" smd rect
			(at 43.0022 -3.9116 270)
			(size 0.0254 0.0254)
			(layers "F.Cu" "F.Mask" "F.Paste")
			(net "P12V")
		)
		(pad "P5" smd rect
			(at 30.48 -3.5306 270)
			(size 9.4488 6.2992)
			(drill
				(offset 0 0.381)
			)
			(layers "F.Cu" "F.Mask" "F.Paste")
			(net "P12V")
		)
		(pad "P6" smd rect
			(at 28.1178 -3.9116 270)
			(size 0.0254 0.0254)
			(layers "F.Cu" "F.Mask" "F.Paste")
			(net "P12V")
		)
		(pad "P7" smd rect
			(at 30.48 -3.9116 270)
			(size 0.0254 0.0254)
			(layers "F.Cu" "F.Mask" "F.Paste")
			(net "P12V")
		)
		(pad "P8" smd rect
			(at 32.8422 -3.9116 270)
			(size 0.0254 0.0254)
			(layers "F.Cu" "F.Mask" "F.Paste")
			(net "P12V")
		)
		(pad "P9" smd rect
			(at 20.32 -3.5306 270)
			(size 9.4488 6.2992)
			(drill
				(offset 0 0.381)
			)
			(layers "F.Cu" "F.Mask" "F.Paste")
			(net "GND")
		)
		(pad "P10" smd rect
			(at 17.9578 -3.9116 270)
			(size 0.0254 0.0254)
			(layers "F.Cu" "F.Mask" "F.Paste")
			(net "GND")
		)
		(pad "P11" smd rect
			(at 20.32 -3.9116 270)
			(size 0.0254 0.0254)
			(layers "F.Cu" "F.Mask" "F.Paste")
			(net "GND")
		)
		(pad "P12" smd rect
			(at 22.6822 -3.9116 270)
			(size 0.0254 0.0254)
			(layers "F.Cu" "F.Mask" "F.Paste")
			(net "GND")
		)
		(pad "P13" smd rect
			(at 10.16 -3.5306 270)
			(size 9.4488 6.2992)
			(drill
				(offset 0 0.381)
			)
			(layers "F.Cu" "F.Mask" "F.Paste")
			(net "GND")
		)
		(pad "P14" smd rect
			(at 7.7978 -3.9116 270)
			(size 0.0254 0.0254)
			(layers "F.Cu" "F.Mask" "F.Paste")
			(net "GND")
		)
		(pad "P15" smd rect
			(at 10.16 -3.9116 270)
			(size 0.0254 0.0254)
			(layers "F.Cu" "F.Mask" "F.Paste")
			(net "GND")
		)
		(pad "P16" smd rect
			(at 12.5222 -3.9116 270)
			(size 0.0254 0.0254)
			(layers "F.Cu" "F.Mask" "F.Paste")
			(net "GND")
		)
		(pad "P17" smd rect
			(at 2.6289 -3.5306 270)
			(size 4.191 6.2992)
			(drill
				(offset 0 0.381)
			)
			(layers "F.Cu" "F.Mask" "F.Paste")
			(net "GND")
		)
		(pad "P18" smd rect
			(at 2.6289 -3.9116 270)
			(size 0.0254 0.0254)
			(layers "F.Cu" "F.Mask" "F.Paste")
			(net "GND")
		)
		(pad "P19" smd rect
			(at 2.6289 -3.1496 270)
			(size 4.191 6.2992)
			(layers "F.Cu" "F.Mask" "F.Paste")
			(net "GND")
		)
		(pad "P20" smd rect
			(at 2.6289 -2.7686 270)
			(size 0.0254 0.0254)
			(layers "F.Cu" "F.Mask" "F.Paste")
			(net "GND")
		)
		(pad "P21" smd rect
			(at 10.16 -3.1496 270)
			(size 9.4488 6.2992)
			(layers "F.Cu" "F.Mask" "F.Paste")
			(net "GND")
		)
		(pad "P22" smd rect
			(at 7.7978 -2.7686 270)
			(size 0.0254 0.0254)
			(layers "F.Cu" "F.Mask" "F.Paste")
			(net "GND")
		)
		(pad "P23" smd rect
			(at 10.16 -2.7686 270)
			(size 0.0254 0.0254)
			(layers "F.Cu" "F.Mask" "F.Paste")
			(net "GND")
		)
		(pad "P24" smd rect
			(at 12.5222 -2.7686 270)
			(size 0.0254 0.0254)
			(layers "F.Cu" "F.Mask" "F.Paste")
			(net "GND")
		)
		(pad "P25" smd rect
			(at 20.32 -3.1496 270)
			(size 9.4488 6.2992)
			(layers "F.Cu" "F.Mask" "F.Paste")
			(net "GND")
		)
		(pad "P26" smd rect
			(at 17.9578 -2.7686 270)
			(size 0.0254 0.0254)
			(layers "F.Cu" "F.Mask" "F.Paste")
			(net "GND")
		)
		(pad "P27" smd rect
			(at 20.32 -2.7686 270)
			(size 0.0254 0.0254)
			(layers "F.Cu" "F.Mask" "F.Paste")
			(net "GND")
		)
		(pad "P28" smd rect
			(at 22.6822 -2.7686 270)
			(size 0.0254 0.0254)
			(layers "F.Cu" "F.Mask" "F.Paste")
			(net "GND")
		)
		(pad "P29" smd rect
			(at 30.48 -3.1496 270)
			(size 9.4488 6.2992)
			(layers "F.Cu" "F.Mask" "F.Paste")
			(net "P12V")
		)
		(pad "P30" smd rect
			(at 28.1178 -2.7686 270)
			(size 0.0254 0.0254)
			(layers "F.Cu" "F.Mask" "F.Paste")
			(net "P12V")
		)
		(pad "P31" smd rect
			(at 30.48 -2.7686 270)
			(size 0.0254 0.0254)
			(layers "F.Cu" "F.Mask" "F.Paste")
			(net "P12V")
		)
		(pad "P32" smd rect
			(at 32.8422 -2.7686 270)
			(size 0.0254 0.0254)
			(layers "F.Cu" "F.Mask" "F.Paste")
			(net "P12V")
		)
		(pad "P33" smd rect
			(at 40.64 -3.1496 270)
			(size 9.4488 6.2992)
			(layers "F.Cu" "F.Mask" "F.Paste")
			(net "P12V")
		)
		(pad "P34" smd rect
			(at 38.2778 -2.7686 270)
			(size 0.0254 0.0254)
			(layers "F.Cu" "F.Mask" "F.Paste")
			(net "P12V")
		)
		(pad "P35" smd rect
			(at 40.64 -2.7686 270)
			(size 0.0254 0.0254)
			(layers "F.Cu" "F.Mask" "F.Paste")
			(net "P12V")
		)
		(pad "P36" smd rect
			(at 43.0022 -2.7686 270)
			(size 0.0254 0.0254)
			(layers "F.Cu" "F.Mask" "F.Paste")
			(net "P12V")
		)
		(pad "S1" smd rect
			(at -2.23012 -2.8829 270)
			(size 0.8128 5.0038)
			(drill
				(offset 0 0.381)
			)
			(layers "F.Cu" "F.Mask" "F.Paste")
			(net "GND")
		)
		(pad "S2" smd rect
			(at -3.50012 -2.8829 270)
			(size 0.8128 5.0038)
			(drill
				(offset 0 0.381)
			)
			(layers "F.Cu" "F.Mask" "F.Paste")
			(net "P3V3")
		)
		(pad "S3" smd rect
			(at -4.77012 -2.8829 270)
			(size 0.8128 5.0038)
			(drill
				(offset 0 0.381)
			)
			(layers "F.Cu" "F.Mask" "F.Paste")
			(net "P3V3")
		)
		(pad "S4" smd rect
			(at -6.04012 -2.8829 270)
			(size 0.8128 5.0038)
			(drill
				(offset 0 0.381)
			)
			(layers "F.Cu" "F.Mask" "F.Paste")
			(net "PEER_TRAY_PRESENT")
		)
		(pad "S5" smd rect
			(at -7.31012 -2.8829 270)
			(size 0.8128 5.0038)
			(drill
				(offset 0 0.381)
			)
			(layers "F.Cu" "F.Mask" "F.Paste")
			(net "PWM_EXP_B")
		)
		(pad "S6" smd rect
			(at -8.58012 -2.8829 270)
			(size 0.8128 5.0038)
			(drill
				(offset 0 0.381)
			)
			(layers "F.Cu" "F.Mask" "F.Paste")
			(net "SELF_TRAY_PRESENT")
		)
		(pad "S7" smd rect
			(at -9.85012 -2.8829 270)
			(size 0.8128 5.0038)
			(drill
				(offset 0 0.381)
			)
			(layers "F.Cu" "F.Mask" "F.Paste")
			(net "PWM_EXP_A")
		)
		(pad "S8" smd rect
			(at -11.12012 -2.8829 270)
			(size 0.8128 5.0038)
			(drill
				(offset 0 0.381)
			)
			(layers "F.Cu" "F.Mask" "F.Paste")
			(net "GND")
		)
		(pad "S9" smd rect
			(at -12.39012 -2.8829 270)
			(size 0.8128 5.0038)
			(drill
				(offset 0 0.381)
			)
			(layers "F.Cu" "F.Mask" "F.Paste")
			(net "STRADDLE_I2C_C_SDA")
		)
		(pad "S10" smd rect
			(at -13.66012 -2.8829 270)
			(size 0.8128 5.0038)
			(drill
				(offset 0 0.381)
			)
			(layers "F.Cu" "F.Mask" "F.Paste")
			(net "GND")
		)
		(pad "S11" smd rect
			(at -14.93012 -2.8829 270)
			(size 0.8128 5.0038)
			(drill
				(offset 0 0.381)
			)
			(layers "F.Cu" "F.Mask" "F.Paste")
			(net "STRADDLE_I2C_C_SCL")
		)
		(pad "S12" smd rect
			(at -16.20012 -2.8829 270)
			(size 0.8128 5.0038)
			(drill
				(offset 0 0.381)
			)
			(layers "F.Cu" "F.Mask" "F.Paste")
			(net "GND")
		)
		(pad "S13" smd rect
			(at -16.20012 -2.5019 270)
			(size 0.8128 5.0038)
			(layers "F.Cu" "F.Mask" "F.Paste")
			(net "GND")
		)
		(pad "S14" smd rect
			(at -14.93012 -2.5019 270)
			(size 0.8128 5.0038)
			(layers "F.Cu" "F.Mask" "F.Paste")
			(net "SELF_1A&2A_HB")
		)
		(pad "S15" smd rect
			(at -13.66012 -2.5019 270)
			(size 0.8128 5.0038)
			(layers "F.Cu" "F.Mask" "F.Paste")
			(net "SELF_1B&2B_HB")
		)
		(pad "S16" smd rect
			(at -12.39012 -2.5019 270)
			(size 0.8128 5.0038)
			(layers "F.Cu" "F.Mask" "F.Paste")
			(net "TRAY_ID")
		)
		(pad "S17" smd rect
			(at -11.12012 -2.5019 270)
			(size 0.8128 5.0038)
			(layers "F.Cu" "F.Mask" "F.Paste")
			(net "FCB_HW_REV")
		)
		(pad "S18" smd rect
			(at -9.85012 -2.5019 270)
			(size 0.8128 5.0038)
			(layers "F.Cu" "F.Mask" "F.Paste")
			(net "SD_LATCH_RELEASE")
		)
		(pad "S19" smd rect
			(at -8.58012 -2.5019 270)
			(size 0.8128 5.0038)
			(layers "F.Cu" "F.Mask" "F.Paste")
			(net "GND")
		)
		(pad "S20" smd rect
			(at -7.31012 -2.5019 270)
			(size 0.8128 5.0038)
			(layers "F.Cu" "F.Mask" "F.Paste")
			(net "PEER_1A&2A_HB")
		)
		(pad "S21" smd rect
			(at -6.04012 -2.5019 270)
			(size 0.8128 5.0038)
			(layers "F.Cu" "F.Mask" "F.Paste")
			(net "PEER_1B&2B_HB")
		)
		(pad "S22" smd rect
			(at -4.77012 -2.5019 270)
			(size 0.8128 5.0038)
			(layers "F.Cu" "F.Mask" "F.Paste")
			(net "GND")
		)
		(pad "S23" smd rect
			(at -3.50012 -2.5019 270)
			(size 0.8128 5.0038)
			(layers "F.Cu" "F.Mask" "F.Paste")
			(net "GND")
		)
		(pad "S24" smd rect
			(at -2.23012 -2.5019 270)
			(size 0.8128 5.0038)
			(layers "F.Cu" "F.Mask" "F.Paste")
			(net "P5VA")
		)
		(zone
			(layer "F.Cu")
			(hatch none 0.5)
			(connect_pads
				(clearance 0)
			)
			(min_thickness 0.25)
			(keepout
				(tracks not_allowed)
				(vias allowed)
				(pads allowed)
				(copperpour not_allowed)
				(footprints allowed)
			)
			(placement
				(enabled no)
				(sheetname "")
			)
			(fill
				(thermal_gap 0.5)
				(thermal_bridge_width 0.5)
				(island_removal_mode 0)
			)
			(polygon
				(pts
					(xy -10.51687 -28.092908) (xy -9.50087 -28.092908) (xy -9.50087 -93.025468) (xy -10.51687 -93.025468)
				)
			)
		)
		(zone
			(layer "F.Cu")
			(hatch none 0.5)
			(connect_pads
				(clearance 0)
			)
			(min_thickness 0.25)
			(keepout
				(tracks allowed)
				(vias not_allowed)
				(pads allowed)
				(copperpour not_allowed)
				(footprints allowed)
			)
			(placement
				(enabled no)
				(sheetname "")
			)
			(fill
				(thermal_gap 0.5)
				(thermal_bridge_width 0.5)
				(island_removal_mode 0)
			)
			(polygon
				(pts
					(xy -10.51687 -28.092908) (xy -2.18567 -28.092908) (xy -2.18567 -93.025468) (xy -10.51687 -93.025468)
				)
			)
		)
		(zone
			(layer "B.Cu")
			(hatch none 0.5)
			(connect_pads
				(clearance 0)
			)
			(min_thickness 0.25)
			(keepout
				(tracks not_allowed)
				(vias allowed)
				(pads allowed)
				(copperpour not_allowed)
				(footprints allowed)
			)
			(placement
				(enabled no)
				(sheetname "")
			)
			(fill
				(thermal_gap 0.5)
				(thermal_bridge_width 0.5)
				(island_removal_mode 0)
			)
			(polygon
				(pts
					(xy -10.51687 -28.092908) (xy -9.50087 -28.092908) (xy -9.50087 -93.025468) (xy -10.51687 -93.025468)
				)
			)
		)
		(zone
			(layer "B.Cu")
			(hatch none 0.5)
			(connect_pads
				(clearance 0)
			)
			(min_thickness 0.25)
			(keepout
				(tracks allowed)
				(vias not_allowed)
				(pads allowed)
				(copperpour not_allowed)
				(footprints allowed)
			)
			(placement
				(enabled no)
				(sheetname "")
			)
			(fill
				(thermal_gap 0.5)
				(thermal_bridge_width 0.5)
				(island_removal_mode 0)
			)
			(polygon
				(pts
					(xy -10.51687 -28.092908) (xy -2.18567 -28.092908) (xy -2.18567 -93.025468) (xy -10.51687 -93.025468)
				)
			)
		)
	)
	(footprint ""
		(layer "F.Cu")
		(at 139.192 -109.474)
		(property "Reference" "R391"
			(at 0 0 0)
			(layer "F.SilkS")
			(hide yes)
			(effects
				(font
					(size 1.27 1.27)
				)
			)
		)
		(property "Value" "0R2J-2-GP"
			(at 0.064008 -3.993896 0)
			(unlocked yes)
			(layer "F.Fab")
			(hide yes)
			(effects
				(font
					(size 1.016 1.016)
					(thickness 0.1524)
				)
			)
		)
		(property "Device Type" "R402H16"
			(at 0.064008 -5.517896 0)
			(unlocked yes)
			(layer "F.Fab")
			(hide yes)
			(effects
				(font
					(size 1.016 1.016)
					(thickness 0.1524)
				)
			)
		)
		(duplicate_pad_numbers_are_jumpers no)
		(fp_line
			(start -0.508 -0.9398)
			(end -0.508 0.9398)
			(stroke
				(width 0.1524)
				(type default)
			)
			(layer "F.SilkS")
		)
		(fp_line
			(start 0.508 -0.9398)
			(end -0.508 -0.9398)
			(stroke
				(width 0.1524)
				(type default)
			)
			(layer "F.SilkS")
		)
		(fp_rect
			(start -0.508 0.9398)
			(end 0.508 -0.9398)
			(stroke
				(width 0)
				(type default)
			)
			(fill no)
			(layer "F.CrtYd")
		)
		(fp_rect
			(start -0.508 0.9398)
			(end 0.508 -0.9398)
			(stroke
				(width 0)
				(type default)
			)
			(fill no)
			(layer "F.Fab")
		)
		(pad "1" smd custom
			(at 0 -0.4445)
			(size 0.1397 0.1397)
			(layers "F.Cu" "F.Mask" "F.Paste")
			(net "TPS2490_EN1")
			(options
				(clearance outline)
				(anchor circle)
			)
			(primitives
				(gr_poly
					(pts
						(arc
							(start -0.1778 -0.2794)
							(mid -0.249642 -0.249642)
							(end -0.2794 -0.1778)
						)
						(arc
							(start -0.2794 0.1778)
							(mid -0.249642 0.249642)
							(end -0.1778 0.2794)
						)
						(arc
							(start 0.1778 0.2794)
							(mid 0.249642 0.249642)
							(end 0.2794 0.1778)
						)
						(arc
							(start 0.2794 -0.1778)
							(mid 0.249642 -0.249642)
							(end 0.1778 -0.2794)
						)
					)
					(width 0)
					(fill yes)
				)
			)
		)
		(pad "2" smd custom
			(at 0 0.4445)
			(size 0.1397 0.1397)
			(layers "F.Cu" "F.Mask" "F.Paste")
			(net "TPS2490_EN2")
			(options
				(clearance outline)
				(anchor circle)
			)
			(primitives
				(gr_poly
					(pts
						(arc
							(start -0.1778 -0.2794)
							(mid -0.249642 -0.249642)
							(end -0.2794 -0.1778)
						)
						(arc
							(start -0.2794 0.1778)
							(mid -0.249642 0.249642)
							(end -0.1778 0.2794)
						)
						(arc
							(start 0.1778 0.2794)
							(mid 0.249642 0.249642)
							(end 0.2794 0.1778)
						)
						(arc
							(start 0.2794 -0.1778)
							(mid 0.249642 -0.249642)
							(end 0.1778 -0.2794)
						)
					)
					(width 0)
					(fill yes)
				)
			)
		)
	)
	(footprint ""
		(layer "F.Cu")
		(at 14.059408 -98.824796)
		(property "Reference" "R370"
			(at 0 0 0)
			(layer "F.SilkS")
			(hide yes)
			(effects
				(font
					(size 1.27 1.27)
				)
			)
		)
		(property "Value" "4K7R2J-2-GP"
			(at 0.064008 -3.993896 0)
			(unlocked yes)
			(layer "F.Fab")
			(hide yes)
			(effects
				(font
					(size 1.016 1.016)
					(thickness 0.1524)
				)
			)
		)
		(property "Device Type" "R402H16"
			(at 0.064008 -5.517896 0)
			(unlocked yes)
			(layer "F.Fab")
			(hide yes)
			(effects
				(font
					(size 1.016 1.016)
					(thickness 0.1524)
				)
			)
		)
		(duplicate_pad_numbers_are_jumpers no)
		(fp_line
			(start -0.508 -0.9398)
			(end -0.508 0.9398)
			(stroke
				(width 0.1524)
				(type default)
			)
			(layer "F.SilkS")
		)
		(fp_line
			(start 0.508 -0.9398)
			(end -0.508 -0.9398)
			(stroke
				(width 0.1524)
				(type default)
			)
			(layer "F.SilkS")
		)
		(fp_rect
			(start -0.508 0.9398)
			(end 0.508 -0.9398)
			(stroke
				(width 0)
				(type default)
			)
			(fill no)
			(layer "F.CrtYd")
		)
		(fp_rect
			(start -0.508 0.9398)
			(end 0.508 -0.9398)
			(stroke
				(width 0)
				(type default)
			)
			(fill no)
			(layer "F.Fab")
		)
		(pad "1" smd custom
			(at 0 -0.4445)
			(size 0.1397 0.1397)
			(layers "F.Cu" "F.Mask" "F.Paste")
			(net "P3V3")
			(options
				(clearance outline)
				(anchor circle)
			)
			(primitives
				(gr_poly
					(pts
						(arc
							(start -0.1778 -0.2794)
							(mid -0.249642 -0.249642)
							(end -0.2794 -0.1778)
						)
						(arc
							(start -0.2794 0.1778)
							(mid -0.249642 0.249642)
							(end -0.1778 0.2794)
						)
						(arc
							(start 0.1778 0.2794)
							(mid 0.249642 0.249642)
							(end 0.2794 0.1778)
						)
						(arc
							(start 0.2794 -0.1778)
							(mid 0.249642 -0.249642)
							(end 0.1778 -0.2794)
						)
					)
					(width 0)
					(fill yes)
				)
			)
		)
		(pad "2" smd custom
			(at 0 0.4445)
			(size 0.1397 0.1397)
			(layers "F.Cu" "F.Mask" "F.Paste")
			(net "I2C_C_BUF_SDAIN")
			(options
				(clearance outline)
				(anchor circle)
			)
			(primitives
				(gr_poly
					(pts
						(arc
							(start -0.1778 -0.2794)
							(mid -0.249642 -0.249642)
							(end -0.2794 -0.1778)
						)
						(arc
							(start -0.2794 0.1778)
							(mid -0.249642 0.249642)
							(end -0.1778 0.2794)
						)
						(arc
							(start 0.1778 0.2794)
							(mid 0.249642 0.249642)
							(end 0.2794 0.1778)
						)
						(arc
							(start 0.2794 -0.1778)
							(mid 0.249642 -0.249642)
							(end 0.1778 -0.2794)
						)
					)
					(width 0)
					(fill yes)
				)
			)
		)
	)
)
